(kicad_pcb
	(version 20260206)
	(generator "pcbnew")
	(generator_version "10.0")
	(general
		(thickness 1.6)
		(legacy_teardrops no)
	)
	(paper "A4")
	(title_block
		(title "04192023_DAF0TMB3IC0_F0TG_MB_C_brd_V02_OCP.brd")
		(comment 1 "Grand Teton / footprints 3299-3306 of 8354")
	)
	(layers
		(0 "F.Cu" signal "TOP")
		(4 "In1.Cu" signal "GND")
		(6 "In2.Cu" signal "IN1")
		(8 "In3.Cu" signal "GND1")
		(10 "In4.Cu" signal "IN2")
		(12 "In5.Cu" signal "GND2")
		(14 "In6.Cu" signal "IN3")
		(16 "In7.Cu" signal "GND3")
		(18 "In8.Cu" signal "VCC")
		(20 "In9.Cu" signal "VCC1")
		(22 "In10.Cu" signal "GND4")
		(24 "In11.Cu" signal "IN4")
		(26 "In12.Cu" signal "GND5")
		(28 "In13.Cu" signal "IN5")
		(30 "In14.Cu" signal "GND6")
		(32 "In15.Cu" signal "IN6")
		(34 "In16.Cu" signal "GND7")
		(2 "B.Cu" signal "BOTTOM")
		(9 "F.Adhes" user "F.Adhesive")
		(11 "B.Adhes" user "B.Adhesive")
		(13 "F.Paste" user "Package Geometry/Pastemask Top")
		(15 "B.Paste" user "Package Geometry/Pastemask Bottom")
		(5 "F.SilkS" user "Ref Des/Silkscreen Top")
		(7 "B.SilkS" user "Ref Des/Silkscreen Bottom")
		(1 "F.Mask" user "Board Geometry/Soldermask Top")
		(3 "B.Mask" user "Board Geometry/Soldermask Bottom")
		(17 "Dwgs.User" user "User.Drawings")
		(19 "Cmts.User" user "User.Comments")
		(21 "Eco1.User" user "User.Eco1")
		(23 "Eco2.User" user "User.Eco2")
		(25 "Edge.Cuts" user "Board Geometry/Outline")
		(27 "Margin" user)
		(31 "F.CrtYd" user "Package Geometry/Place Bound Top")
		(29 "B.CrtYd" user "Package Geometry/Place Bound Bottom")
		(35 "F.Fab" user "Ref Des/Assembly Top")
		(33 "B.Fab" user "Ref Des/Assembly Bottom")
	)
	(footprint ""
		(layer "F.Cu")
		(at 196.536564 -69.423788 -90)
		(property "Reference" "PU293"
			(at -3.945128 3.01625 0)
			(unlocked yes)
			(layer "F.SilkS")
			(effects
				(font
					(size 0.7874 0.5842)
					(thickness 0.1524)
				)
			)
		)
		(property "Value" ""
			(at 0 0 270)
			(layer "F.Fab")
			(effects
				(font
					(size 1.27 1.27)
				)
			)
		)
		(duplicate_pad_numbers_are_jumpers no)
		(fp_line
			(start -1.239774 1.495298)
			(end -1.239774 -1.495298)
			(stroke
				(width 0.1524)
				(type default)
			)
			(layer "F.SilkS")
		)
		(fp_line
			(start 1.239774 1.495298)
			(end -1.239774 1.495298)
			(stroke
				(width 0.1524)
				(type default)
			)
			(layer "F.SilkS")
		)
		(fp_line
			(start -1.239774 -1.495298)
			(end 1.239774 -1.495298)
			(stroke
				(width 0.1524)
				(type default)
			)
			(layer "F.SilkS")
		)
		(fp_line
			(start 1.239774 -1.495298)
			(end 1.239774 1.495298)
			(stroke
				(width 0.1524)
				(type default)
			)
			(layer "F.SilkS")
		)
		(fp_poly
			(pts
				(xy -2.047748 -0.638302) (xy -3.163824 -0.849122) (xy -2.54889 -1.657858)
			)
			(stroke
				(width 0)
				(type default)
			)
			(fill yes)
			(layer "F.SilkS")
		)
		(fp_line
			(start -0.8001 1.050036)
			(end -0.8001 -1.050036)
			(stroke
				(width 0.1)
				(type default)
			)
			(layer "F.Fab")
		)
		(fp_line
			(start 0.8001 1.050036)
			(end -0.8001 1.050036)
			(stroke
				(width 0.1)
				(type default)
			)
			(layer "F.Fab")
		)
		(fp_line
			(start -0.8001 -1.050036)
			(end 0.8001 -1.050036)
			(stroke
				(width 0.1)
				(type default)
			)
			(layer "F.Fab")
		)
		(fp_line
			(start 0.8001 -1.050036)
			(end 0.8001 1.050036)
			(stroke
				(width 0.1)
				(type default)
			)
			(layer "F.Fab")
		)
		(fp_poly
			(pts
				(xy -2.458974 -0.508) (xy -2.458974 0.508) (xy -1.442974 0)
			)
			(stroke
				(width 0)
				(type default)
			)
			(fill yes)
			(layer "F.Fab")
		)
		(pad "1_2" smd circle
			(at -0.374904 0)
			(size 0 0)
			(layers "F.Cu" "F.Mask" "F.Paste")
			(net "P3V3_AUX")
		)
		(pad "3" smd rect
			(at -0.499872 0.999998 270)
			(size 0.254 0.7112)
			(layers "F.Cu" "F.Mask" "F.Paste")
			(net "GND")
		)
		(pad "4" smd rect
			(at 0 0.999998 270)
			(size 0.254 0.7112)
			(layers "F.Cu" "F.Mask" "F.Paste")
			(net "P3V3_E1S_ILIMIT_0")
		)
		(pad "5" smd rect
			(at 0.499872 0.999998 270)
			(size 0.254 0.7112)
			(layers "F.Cu" "F.Mask" "F.Paste")
			(net "P3V3_E1S_MODE_0")
		)
		(pad "6_7" smd circle
			(at 0.374904 0 180)
			(size 0 0)
			(layers "F.Cu" "F.Mask" "F.Paste")
			(net "P3V3_E1S_0_R")
		)
		(pad "8" smd rect
			(at 0.499872 -0.999998 270)
			(size 0.254 0.7112)
			(layers "F.Cu" "F.Mask" "F.Paste")
			(net "P3V3_E1S_GATE_0_PU293")
		)
		(pad "9" smd rect
			(at 0 -0.999998 270)
			(size 0.254 0.7112)
			(layers "F.Cu" "F.Mask" "F.Paste")
			(net "P3V3_E1S_EN_0_R2")
		)
		(pad "10" smd rect
			(at -0.499872 -0.999998 270)
			(size 0.254 0.7112)
			(layers "F.Cu" "F.Mask" "F.Paste")
			(net "P3V3_E1S_DVDT_0")
		)
	)
	(footprint ""
		(layer "F.Cu")
		(at 205.262226 -125.817376)
		(property "Reference" "R6061"
			(at 0 0 0)
			(layer "F.SilkS")
			(hide yes)
			(effects
				(font
					(size 1.27 1.27)
				)
			)
		)
		(property "Value" ""
			(at 0 0 0)
			(layer "F.Fab")
			(effects
				(font
					(size 1.27 1.27)
				)
			)
		)
		(duplicate_pad_numbers_are_jumpers no)
		(fp_line
			(start -0.7874 -0.4064)
			(end 0.7874 -0.4064)
			(stroke
				(width 0.1524)
				(type default)
			)
			(layer "F.SilkS")
		)
		(fp_line
			(start -0.7874 0.4064)
			(end -0.7874 -0.4064)
			(stroke
				(width 0.1524)
				(type default)
			)
			(layer "F.SilkS")
		)
		(fp_line
			(start 0.7874 -0.4064)
			(end 0.7874 0.4064)
			(stroke
				(width 0.1524)
				(type default)
			)
			(layer "F.SilkS")
		)
		(fp_line
			(start 0.7874 0.4064)
			(end -0.7874 0.4064)
			(stroke
				(width 0.1524)
				(type default)
			)
			(layer "F.SilkS")
		)
		(fp_line
			(start -0.67945 -0.305054)
			(end -0.12065 -0.305054)
			(stroke
				(width 0.1)
				(type default)
			)
			(layer "F.Fab")
		)
		(fp_line
			(start -0.67945 0.3048)
			(end -0.67945 -0.305054)
			(stroke
				(width 0.1)
				(type default)
			)
			(layer "F.Fab")
		)
		(fp_line
			(start -0.12065 -0.305054)
			(end -0.12065 -0.2794)
			(stroke
				(width 0.1)
				(type default)
			)
			(layer "F.Fab")
		)
		(fp_line
			(start -0.12065 -0.2794)
			(end 0.12065 -0.2794)
			(stroke
				(width 0.1)
				(type default)
			)
			(layer "F.Fab")
		)
		(fp_line
			(start -0.12065 0.2794)
			(end -0.12065 0.3048)
			(stroke
				(width 0.1)
				(type default)
			)
			(layer "F.Fab")
		)
		(fp_line
			(start -0.12065 0.3048)
			(end -0.67945 0.3048)
			(stroke
				(width 0.1)
				(type default)
			)
			(layer "F.Fab")
		)
		(fp_line
			(start 0.120396 0.2794)
			(end -0.12065 0.2794)
			(stroke
				(width 0.1)
				(type default)
			)
			(layer "F.Fab")
		)
		(fp_line
			(start 0.120396 0.3048)
			(end 0.120396 0.2794)
			(stroke
				(width 0.1)
				(type default)
			)
			(layer "F.Fab")
		)
		(fp_line
			(start 0.12065 -0.3048)
			(end 0.67945 -0.3048)
			(stroke
				(width 0.1)
				(type default)
			)
			(layer "F.Fab")
		)
		(fp_line
			(start 0.12065 -0.2794)
			(end 0.12065 -0.3048)
			(stroke
				(width 0.1)
				(type default)
			)
			(layer "F.Fab")
		)
		(fp_line
			(start 0.67945 -0.3048)
			(end 0.67945 0.3048)
			(stroke
				(width 0.1)
				(type default)
			)
			(layer "F.Fab")
		)
		(fp_line
			(start 0.67945 0.3048)
			(end 0.120396 0.3048)
			(stroke
				(width 0.1)
				(type default)
			)
			(layer "F.Fab")
		)
		(pad "1" smd circle
			(at -0.40005 0)
			(size 0 0)
			(layers "F.Cu" "F.Mask" "F.Paste")
			(net "P12V_OCP_V3_2_EN_R")
		)
		(pad "2" smd circle
			(at 0.40005 0)
			(size 0 0)
			(layers "F.Cu" "F.Mask" "F.Paste")
			(net "P3V3_AUX")
		)
	)
	(footprint ""
		(layer "F.Cu")
		(at 197.269608 -107.529376 180)
		(property "Reference" "R225"
			(at 0 0 180)
			(layer "F.SilkS")
			(hide yes)
			(effects
				(font
					(size 1.27 1.27)
				)
			)
		)
		(property "Value" ""
			(at 0 0 180)
			(layer "F.Fab")
			(effects
				(font
					(size 1.27 1.27)
				)
			)
		)
		(duplicate_pad_numbers_are_jumpers no)
		(fp_line
			(start 0.7874 0.4064)
			(end -0.7874 0.4064)
			(stroke
				(width 0.1524)
				(type default)
			)
			(layer "F.SilkS")
		)
		(fp_line
			(start 0.7874 -0.4064)
			(end 0.7874 0.4064)
			(stroke
				(width 0.1524)
				(type default)
			)
			(layer "F.SilkS")
		)
		(fp_line
			(start -0.7874 0.4064)
			(end -0.7874 -0.4064)
			(stroke
				(width 0.1524)
				(type default)
			)
			(layer "F.SilkS")
		)
		(fp_line
			(start -0.7874 -0.4064)
			(end 0.7874 -0.4064)
			(stroke
				(width 0.1524)
				(type default)
			)
			(layer "F.SilkS")
		)
		(fp_line
			(start 0.67945 0.3048)
			(end 0.120396 0.3048)
			(stroke
				(width 0.1)
				(type default)
			)
			(layer "F.Fab")
		)
		(fp_line
			(start 0.67945 -0.3048)
			(end 0.67945 0.3048)
			(stroke
				(width 0.1)
				(type default)
			)
			(layer "F.Fab")
		)
		(fp_line
			(start 0.12065 -0.2794)
			(end 0.12065 -0.3048)
			(stroke
				(width 0.1)
				(type default)
			)
			(layer "F.Fab")
		)
		(fp_line
			(start 0.12065 -0.3048)
			(end 0.67945 -0.3048)
			(stroke
				(width 0.1)
				(type default)
			)
			(layer "F.Fab")
		)
		(fp_line
			(start 0.120396 0.3048)
			(end 0.120396 0.2794)
			(stroke
				(width 0.1)
				(type default)
			)
			(layer "F.Fab")
		)
		(fp_line
			(start 0.120396 0.2794)
			(end -0.12065 0.2794)
			(stroke
				(width 0.1)
				(type default)
			)
			(layer "F.Fab")
		)
		(fp_line
			(start -0.12065 0.3048)
			(end -0.67945 0.3048)
			(stroke
				(width 0.1)
				(type default)
			)
			(layer "F.Fab")
		)
		(fp_line
			(start -0.12065 0.2794)
			(end -0.12065 0.3048)
			(stroke
				(width 0.1)
				(type default)
			)
			(layer "F.Fab")
		)
		(fp_line
			(start -0.12065 -0.2794)
			(end 0.12065 -0.2794)
			(stroke
				(width 0.1)
				(type default)
			)
			(layer "F.Fab")
		)
		(fp_line
			(start -0.12065 -0.305054)
			(end -0.12065 -0.2794)
			(stroke
				(width 0.1)
				(type default)
			)
			(layer "F.Fab")
		)
		(fp_line
			(start -0.67945 0.3048)
			(end -0.67945 -0.305054)
			(stroke
				(width 0.1)
				(type default)
			)
			(layer "F.Fab")
		)
		(fp_line
			(start -0.67945 -0.305054)
			(end -0.12065 -0.305054)
			(stroke
				(width 0.1)
				(type default)
			)
			(layer "F.Fab")
		)
		(pad "1" smd circle
			(at -0.40005 0 180)
			(size 0 0)
			(layers "F.Cu" "F.Mask" "F.Paste")
			(net "PWRGD_PVDD33_S5")
		)
		(pad "2" smd circle
			(at 0.40005 0 180)
			(size 0 0)
			(layers "F.Cu" "F.Mask" "F.Paste")
			(net "FM_PWRGD_PVDD33_S5")
		)
	)
	(footprint ""
		(layer "F.Cu")
		(at 39.95801 -438.531 180)
		(property "Reference" "R3466"
			(at 0 0 180)
			(layer "F.SilkS")
			(hide yes)
			(effects
				(font
					(size 1.27 1.27)
				)
			)
		)
		(property "Value" ""
			(at 0 0 180)
			(layer "F.Fab")
			(effects
				(font
					(size 1.27 1.27)
				)
			)
		)
		(duplicate_pad_numbers_are_jumpers no)
		(fp_line
			(start 0.7874 0.4064)
			(end -0.7874 0.4064)
			(stroke
				(width 0.1524)
				(type default)
			)
			(layer "F.SilkS")
		)
		(fp_line
			(start 0.7874 -0.4064)
			(end 0.7874 0.4064)
			(stroke
				(width 0.1524)
				(type default)
			)
			(layer "F.SilkS")
		)
		(fp_line
			(start -0.7874 0.4064)
			(end -0.7874 -0.4064)
			(stroke
				(width 0.1524)
				(type default)
			)
			(layer "F.SilkS")
		)
		(fp_line
			(start -0.7874 -0.4064)
			(end 0.7874 -0.4064)
			(stroke
				(width 0.1524)
				(type default)
			)
			(layer "F.SilkS")
		)
		(fp_line
			(start 0.67945 0.3048)
			(end 0.120396 0.3048)
			(stroke
				(width 0.1)
				(type default)
			)
			(layer "F.Fab")
		)
		(fp_line
			(start 0.67945 -0.3048)
			(end 0.67945 0.3048)
			(stroke
				(width 0.1)
				(type default)
			)
			(layer "F.Fab")
		)
		(fp_line
			(start 0.12065 -0.2794)
			(end 0.12065 -0.3048)
			(stroke
				(width 0.1)
				(type default)
			)
			(layer "F.Fab")
		)
		(fp_line
			(start 0.12065 -0.3048)
			(end 0.67945 -0.3048)
			(stroke
				(width 0.1)
				(type default)
			)
			(layer "F.Fab")
		)
		(fp_line
			(start 0.120396 0.3048)
			(end 0.120396 0.2794)
			(stroke
				(width 0.1)
				(type default)
			)
			(layer "F.Fab")
		)
		(fp_line
			(start 0.120396 0.2794)
			(end -0.12065 0.2794)
			(stroke
				(width 0.1)
				(type default)
			)
			(layer "F.Fab")
		)
		(fp_line
			(start -0.12065 0.3048)
			(end -0.67945 0.3048)
			(stroke
				(width 0.1)
				(type default)
			)
			(layer "F.Fab")
		)
		(fp_line
			(start -0.12065 0.2794)
			(end -0.12065 0.3048)
			(stroke
				(width 0.1)
				(type default)
			)
			(layer "F.Fab")
		)
		(fp_line
			(start -0.12065 -0.2794)
			(end 0.12065 -0.2794)
			(stroke
				(width 0.1)
				(type default)
			)
			(layer "F.Fab")
		)
		(fp_line
			(start -0.12065 -0.305054)
			(end -0.12065 -0.2794)
			(stroke
				(width 0.1)
				(type default)
			)
			(layer "F.Fab")
		)
		(fp_line
			(start -0.67945 0.3048)
			(end -0.67945 -0.305054)
			(stroke
				(width 0.1)
				(type default)
			)
			(layer "F.Fab")
		)
		(fp_line
			(start -0.67945 -0.305054)
			(end -0.12065 -0.305054)
			(stroke
				(width 0.1)
				(type default)
			)
			(layer "F.Fab")
		)
		(pad "1" smd circle
			(at -0.40005 0 180)
			(size 0 0)
			(layers "F.Cu" "F.Mask" "F.Paste")
			(net "RST_PERST_1_SWB_BUF_R_N")
		)
		(pad "2" smd circle
			(at 0.40005 0 180)
			(size 0 0)
			(layers "F.Cu" "F.Mask" "F.Paste")
			(net "GND")
		)
	)
	(footprint ""
		(layer "F.Cu")
		(at 295.576752 -422.173908 90)
		(property "Reference" "R669"
			(at 0 0 90)
			(layer "F.SilkS")
			(hide yes)
			(effects
				(font
					(size 1.27 1.27)
				)
			)
		)
		(property "Value" ""
			(at 0 0 90)
			(layer "F.Fab")
			(effects
				(font
					(size 1.27 1.27)
				)
			)
		)
		(duplicate_pad_numbers_are_jumpers no)
		(fp_line
			(start 0.32512 -0.175006)
			(end 0.32512 0.175006)
			(stroke
				(width 0.1)
				(type default)
			)
			(layer "F.Fab")
		)
		(fp_line
			(start -0.32512 -0.175006)
			(end 0.32512 -0.175006)
			(stroke
				(width 0.1)
				(type default)
			)
			(layer "F.Fab")
		)
		(fp_line
			(start 0.32512 0.175006)
			(end -0.32512 0.175006)
			(stroke
				(width 0.1)
				(type default)
			)
			(layer "F.Fab")
		)
		(fp_line
			(start -0.32512 0.175006)
			(end -0.32512 -0.175006)
			(stroke
				(width 0.1)
				(type default)
			)
			(layer "F.Fab")
		)
		(pad "1" smd rect
			(at -0.2667 0 90)
			(size 0.3048 0.381)
			(layers "F.Cu" "F.Mask" "F.Paste")
			(net "SMB_RT_CPU0_P0_ROM_R_SDA")
		)
		(pad "2" smd rect
			(at 0.2667 0 270)
			(size 0.3048 0.381)
			(layers "F.Cu" "F.Mask" "F.Paste")
			(net "SMB_RT_CPU0_P0_ROM_SDA")
		)
	)
	(footprint ""
		(layer "F.Cu")
		(at 136.840976 -379.471428)
		(property "Reference" "C49"
			(at 0 0 0)
			(layer "F.SilkS")
			(hide yes)
			(effects
				(font
					(size 1.27 1.27)
				)
			)
		)
		(property "Value" ""
			(at 0 0 0)
			(layer "F.Fab")
			(effects
				(font
					(size 1.27 1.27)
				)
			)
		)
		(duplicate_pad_numbers_are_jumpers no)
		(fp_line
			(start -0.299974 -0.150114)
			(end 0.299974 -0.150114)
			(stroke
				(width 0.1)
				(type default)
			)
			(layer "F.Fab")
		)
		(fp_line
			(start -0.299974 0.150114)
			(end -0.299974 -0.150114)
			(stroke
				(width 0.1)
				(type default)
			)
			(layer "F.Fab")
		)
		(fp_line
			(start 0.299974 -0.150114)
			(end 0.299974 0.150114)
			(stroke
				(width 0.1)
				(type default)
			)
			(layer "F.Fab")
		)
		(fp_line
			(start 0.299974 0.150114)
			(end -0.299974 0.150114)
			(stroke
				(width 0.1)
				(type default)
			)
			(layer "F.Fab")
		)
		(pad "1" smd rect
			(at -0.2667 0)
			(size 0.3048 0.381)
			(layers "F.Cu" "F.Mask" "F.Paste")
			(net "P5E_CPU1_P3_TX_C_DP<15>")
		)
		(pad "2" smd rect
			(at 0.2667 0)
			(size 0.3048 0.381)
			(layers "F.Cu" "F.Mask" "F.Paste")
			(net "P5E_CPU1_P3_TX_DP<15>")
		)
	)
	(footprint ""
		(layer "F.Cu")
		(at 372.937278 -142.488158)
		(property "Reference" "R8298"
			(at 0 0 0)
			(layer "F.SilkS")
			(hide yes)
			(effects
				(font
					(size 1.27 1.27)
				)
			)
		)
		(property "Value" ""
			(at 0 0 0)
			(layer "F.Fab")
			(effects
				(font
					(size 1.27 1.27)
				)
			)
		)
		(duplicate_pad_numbers_are_jumpers no)
		(fp_line
			(start -0.7874 -0.4064)
			(end 0.7874 -0.4064)
			(stroke
				(width 0.1524)
				(type default)
			)
			(layer "F.SilkS")
		)
		(fp_line
			(start -0.7874 0.4064)
			(end -0.7874 -0.4064)
			(stroke
				(width 0.1524)
				(type default)
			)
			(layer "F.SilkS")
		)
		(fp_line
			(start 0.7874 -0.4064)
			(end 0.7874 0.4064)
			(stroke
				(width 0.1524)
				(type default)
			)
			(layer "F.SilkS")
		)
		(fp_line
			(start 0.7874 0.4064)
			(end -0.7874 0.4064)
			(stroke
				(width 0.1524)
				(type default)
			)
			(layer "F.SilkS")
		)
		(fp_line
			(start -0.67945 -0.305054)
			(end -0.12065 -0.305054)
			(stroke
				(width 0.1)
				(type default)
			)
			(layer "F.Fab")
		)
		(fp_line
			(start -0.67945 0.3048)
			(end -0.67945 -0.305054)
			(stroke
				(width 0.1)
				(type default)
			)
			(layer "F.Fab")
		)
		(fp_line
			(start -0.12065 -0.305054)
			(end -0.12065 -0.2794)
			(stroke
				(width 0.1)
				(type default)
			)
			(layer "F.Fab")
		)
		(fp_line
			(start -0.12065 -0.2794)
			(end 0.12065 -0.2794)
			(stroke
				(width 0.1)
				(type default)
			)
			(layer "F.Fab")
		)
		(fp_line
			(start -0.12065 0.2794)
			(end -0.12065 0.3048)
			(stroke
				(width 0.1)
				(type default)
			)
			(layer "F.Fab")
		)
		(fp_line
			(start -0.12065 0.3048)
			(end -0.67945 0.3048)
			(stroke
				(width 0.1)
				(type default)
			)
			(layer "F.Fab")
		)
		(fp_line
			(start 0.120396 0.2794)
			(end -0.12065 0.2794)
			(stroke
				(width 0.1)
				(type default)
			)
			(layer "F.Fab")
		)
		(fp_line
			(start 0.120396 0.3048)
			(end 0.120396 0.2794)
			(stroke
				(width 0.1)
				(type default)
			)
			(layer "F.Fab")
		)
		(fp_line
			(start 0.12065 -0.3048)
			(end 0.67945 -0.3048)
			(stroke
				(width 0.1)
				(type default)
			)
			(layer "F.Fab")
		)
		(fp_line
			(start 0.12065 -0.2794)
			(end 0.12065 -0.3048)
			(stroke
				(width 0.1)
				(type default)
			)
			(layer "F.Fab")
		)
		(fp_line
			(start 0.67945 -0.3048)
			(end 0.67945 0.3048)
			(stroke
				(width 0.1)
				(type default)
			)
			(layer "F.Fab")
		)
		(fp_line
			(start 0.67945 0.3048)
			(end 0.120396 0.3048)
			(stroke
				(width 0.1)
				(type default)
			)
			(layer "F.Fab")
		)
		(pad "1" smd circle
			(at -0.40005 0)
			(size 0 0)
			(layers "F.Cu" "F.Mask" "F.Paste")
			(net "P3V3_AUX")
		)
		(pad "2" smd circle
			(at 0.40005 0)
			(size 0 0)
			(layers "F.Cu" "F.Mask" "F.Paste")
			(net "PWRGD_PVDDCR_SOC_P0_R")
		)
	)
	(footprint ""
		(layer "F.Cu")
		(at 42.967402 -381.48006 180)
		(property "Reference" "C836"
			(at 0 0 180)
			(layer "F.SilkS")
			(hide yes)
			(effects
				(font
					(size 1.27 1.27)
				)
			)
		)
		(property "Value" ""
			(at 0 0 180)
			(layer "F.Fab")
			(effects
				(font
					(size 1.27 1.27)
				)
			)
		)
		(duplicate_pad_numbers_are_jumpers no)
		(fp_line
			(start 0.299974 0.150114)
			(end -0.299974 0.150114)
			(stroke
				(width 0.1)
				(type default)
			)
			(layer "F.Fab")
		)
		(fp_line
			(start 0.299974 -0.150114)
			(end 0.299974 0.150114)
			(stroke
				(width 0.1)
				(type default)
			)
			(layer "F.Fab")
		)
		(fp_line
			(start -0.299974 0.150114)
			(end -0.299974 -0.150114)
			(stroke
				(width 0.1)
				(type default)
			)
			(layer "F.Fab")
		)
		(fp_line
			(start -0.299974 -0.150114)
			(end 0.299974 -0.150114)
			(stroke
				(width 0.1)
				(type default)
			)
			(layer "F.Fab")
		)
		(pad "1" smd rect
			(at -0.2667 0 180)
			(size 0.3048 0.381)
			(layers "F.Cu" "F.Mask" "F.Paste")
			(net "P5E_CPU1_P0_TX_C_DN<0>")
		)
		(pad "2" smd rect
			(at 0.2667 0 180)
			(size 0.3048 0.381)
			(layers "F.Cu" "F.Mask" "F.Paste")
			(net "P5E_CPU1_P0_TX_DN<0>")
		)
	)
)
